(kicad_pcb
	(version 20211014)
	(generator pcbnew)
	(general
    (thickness 1.6)
  )
	(paper "A4")
	(title_block
    (title "SA800U (Snapdragon 845) Baseboard")
    (date "2023-10-19")
    (rev "1.0.3")
    (company "Antmicro Ltd.")
    (comment 1 "www.antmicro.com")
		(comment 9 "footprints 332-340 of 589")
	)
	(layers
    (0 "F.Cu" signal)
    (1 "In1.Cu" power)
    (2 "In2.Cu" signal)
    (3 "In3.Cu" signal)
    (4 "In4.Cu" power)
    (31 "B.Cu" signal)
    (32 "B.Adhes" user "B.Adhesive")
    (33 "F.Adhes" user "F.Adhesive")
    (34 "B.Paste" user)
    (35 "F.Paste" user)
    (36 "B.SilkS" user "B.Silkscreen")
    (37 "F.SilkS" user "F.Silkscreen")
    (38 "B.Mask" user)
    (39 "F.Mask" user)
    (40 "Dwgs.User" user "User.Drawings")
    (41 "Cmts.User" user "User.Comments")
    (42 "Eco1.User" user "User.Eco1")
    (43 "Eco2.User" user "User.Eco2")
    (44 "Edge.Cuts" user)
    (45 "Margin" user)
    (46 "B.CrtYd" user "B.Courtyard")
    (47 "F.CrtYd" user "F.Courtyard")
    (48 "B.Fab" user)
    (49 "F.Fab" user)
  )
	(footprint "sa800u-baseboard-hw-footprints:R_0402_1005Metric" (layer "B.Cu")
    (tedit 5FD9C158)
    (at 123.8 124.35 180)
    (descr "Resistor SMD 0402")
    (tags "resistor SMD 0402")
    (property "Author" "Antmicro")
    (property "DNP" "DNP")
    (property "License" "Apache-2.0")
    (property "MPN" "CR0402-FX-1002GLF")
    (property "Manufacturer" "Bourns")
    (property "Sheetfile" "psu.kicad_sch")
    (property "Sheetname" "PSU")
    (property "Tolerance" "1%")
    (property "Val" "10k")
    (attr exclude_from_pos_files)
    (fp_text reference "R133" (at -1.14 -1.28) (layer "B.SilkS")
      (effects (font (size 0.7 0.7) (thickness 0.15)) (justify left bottom mirror))
    )
    (fp_text value "R_10k_0402" (at 0 -1.4) (layer "B.Fab")
      (effects (font (size 0.7 0.7) (thickness 0.15)) (justify left bottom mirror))
    )
    (fp_text user "License: Apache-2.0" (at -0.95 -5.169) (layer "B.Fab") hide
      (effects (font (size 0.7 0.7) (thickness 0.15)) (justify left bottom mirror))
    )
    (fp_text user "${REFERENCE}" (at -0.95 -3.168) (layer "B.Fab") hide
      (effects (font (size 0.7 0.7) (thickness 0.15)) (justify left bottom mirror))
    )
    (fp_text user "Author: Antmicro" (at -0.95 -4.169) (layer "B.Fab") hide
      (effects (font (size 0.7 0.7) (thickness 0.15)) (justify left bottom mirror))
    )
    (fp_rect (start -0.93 0.47) (end 0.93 -0.47) (layer "B.CrtYd") (width 0.05) (fill none))
    (fp_rect (start -0.5 0.25) (end 0.5 -0.25) (layer "B.Fab") (width 0.15) (fill none))
    (pad "1" smd roundrect (at -0.485 0 180) (size 0.59 0.64) (layers "B.Cu" "B.Paste" "B.Mask") (roundrect_rratio 0.25)
      (net 133 "5V_SYS") (pintype "passive"))
    (pad "2" smd roundrect (at 0.485 0 180) (size 0.59 0.64) (layers "B.Cu" "B.Paste" "B.Mask") (roundrect_rratio 0.25)
      (net 408 "Net-(R128-Pad2)") (pintype "passive"))
  )
	(footprint "sa800u-baseboard-hw-footprints:L_Coilcraft_XEL4030" (layer "B.Cu")
    (tedit 6215D867)
    (at 129.026 121.88)
    (property "Author" "Antmicro")
    (property "IMax" "")
    (property "ISat" "")
    (property "License" "Apache-2.0")
    (property "MPN" "XEL4030-222MEC")
    (property "Manufacturer" "Coilcraft")
    (property "MaxCur" "6.1A")
    (property "Sheetfile" "psu.kicad_sch")
    (property "Sheetname" "PSU")
    (property "Size" "4x4")
    (property "Val" "2u2/6.1A")
    (attr smd)
    (fp_text reference "L28" (at 0.935 -2.52 180) (layer "B.SilkS")
      (effects (font (size 0.7 0.7) (thickness 0.15)) (justify left bottom mirror))
    )
    (fp_text value "L_2u2_6.1A_XEL4030" (at 0 -3.35 180) (layer "B.Fab")
      (effects (font (size 0.7 0.7) (thickness 0.15)) (justify left bottom mirror))
    )
    (fp_text user "Author: Antmicro" (at -2.15 -5.996 180) (layer "B.Fab") hide
      (effects (font (size 0.7 0.7) (thickness 0.15)) (justify left bottom mirror))
    )
    (fp_text user "License: Apache-2.0" (at -2.15 -6.996 180) (layer "B.Fab") hide
      (effects (font (size 0.7 0.7) (thickness 0.15)) (justify left bottom mirror))
    )
    (fp_text user "${REFERENCE}" (at -2.15 -4.996 180) (layer "B.Fab") hide
      (effects (font (size 0.7 0.7) (thickness 0.15)) (justify left bottom mirror))
    )
    (fp_line (start -1.8 -2.2) (end 1.85 -2.199) (layer "B.SilkS") (width 0.15))
    (fp_line (start -1.8 2.2) (end 1.85 2.201) (layer "B.SilkS") (width 0.15))
    (fp_rect (start -2.45 2.45) (end 2.45 -2.45) (layer "B.CrtYd") (width 0.05) (fill none))
    (fp_line (start 1.999 2) (end 1.999 -1.999) (layer "B.Fab") (width 0.15))
    (fp_line (start -2 -1.999) (end -2 2) (layer "B.Fab") (width 0.15))
    (fp_line (start -2 2) (end 1.999 2) (layer "B.Fab") (width 0.15))
    (fp_line (start 1.999 -1.999) (end -2 -1.999) (layer "B.Fab") (width 0.15))
    (pad "1" smd rect (at -1.186 0) (size 0.98 3.4) (layers "B.Cu" "B.Paste" "B.Mask")
      (net 360 "Net-(C134-Pad2)") (pintype "passive"))
    (pad "2" smd rect (at 1.185 0) (size 0.98 3.4) (layers "B.Cu" "B.Paste" "B.Mask")
      (net 138 "1V2_SYS") (pintype "passive"))
  )
	(footprint "sa800u-baseboard-hw-footprints:AP62301WU-7-TSOT23-6" (layer "B.Cu")
    (tedit 6215EA50)
    (at 124.85 121.95 -90)
    (property "Author" "Antmicro")
    (property "License" "Apache-2.0")
    (property "MPN" "AP62301WU-7")
    (property "Manufacturer" "Diodes Incorporated")
    (property "Sheetfile" "psu.kicad_sch")
    (property "Sheetname" "PSU")
    (attr smd)
    (fp_text reference "U21" (at -1.79 -1.1 180) (layer "B.SilkS")
      (effects (font (size 0.7 0.7) (thickness 0.15)) (justify left bottom mirror))
    )
    (fp_text value "AP62301WU-7" (at -0.005 -2.6 90) (layer "B.Fab")
      (effects (font (size 0.7 0.7) (thickness 0.15)) (justify left bottom mirror))
    )
    (fp_text user "License: Apache-2.0" (at -1.893 -4.967 90) (layer "B.Fab") hide
      (effects (font (size 0.7 0.7) (thickness 0.15)) (justify left bottom mirror))
    )
    (fp_text user "Author: Antmicro" (at -1.893 -7.368 90) (layer "B.Fab") hide
      (effects (font (size 0.7 0.7) (thickness 0.15)) (justify left bottom mirror))
    )
    (fp_text user "${REFERENCE}" (at -1.893 -6.168 90) (layer "B.Fab") hide
      (effects (font (size 0.7 0.7) (thickness 0.15)) (justify left bottom mirror))
    )
    (fp_line (start -1.4805 -0.725) (end -1.4795 0.725) (layer "B.SilkS") (width 0.15))
    (fp_line (start -1.4805 -0.725) (end -1.3905 -0.725) (layer "B.SilkS") (width 0.15))
    (fp_line (start 1.48 0.72) (end 1.479 -0.73) (layer "B.SilkS") (width 0.15))
    (fp_line (start -1.4795 0.725) (end -1.3905 0.725) (layer "B.SilkS") (width 0.15))
    (fp_line (start 1.48 0.72) (end 1.38 0.72) (layer "B.SilkS") (width 0.15))
    (fp_line (start 1.479 -0.73) (end 1.38 -0.73) (layer "B.SilkS") (width 0.15))
    (fp_circle (center -1.499 -1.236) (end -1.45 -1.236) (layer "B.SilkS") (width 0.15) (fill solid))
    (fp_rect (start -1.65 1.61) (end 1.65 -1.61) (layer "B.CrtYd") (width 0.05) (fill none))
    (fp_line (start 1.523 0.833) (end 1.523 -0.916) (layer "B.Fab") (width 0.15))
    (fp_line (start -1.527 -0.491) (end -1.527 0.833) (layer "B.Fab") (width 0.15))
    (fp_line (start -1.527 -0.491) (end -1.102 -0.916) (layer "B.Fab") (width 0.15))
    (fp_line (start -1.102 -0.916) (end 1.523 -0.916) (layer "B.Fab") (width 0.15))
    (fp_line (start -1.527 0.833) (end 1.523 0.833) (layer "B.Fab") (width 0.15))
    (pad "1" smd rect (at -0.952 -1.18 270) (size 0.7 0.8) (layers "B.Cu" "B.Paste" "B.Mask")
      (net 1 "GND") (pinfunction "GND") (pintype "power_in"))
    (pad "2" smd rect (at -0.001 -1.18 270) (size 0.7 0.8) (layers "B.Cu" "B.Paste" "B.Mask")
      (net 360 "Net-(C134-Pad2)") (pinfunction "SW") (pintype "power_out"))
    (pad "3" smd rect (at 0.947 -1.18 270) (size 0.7 0.8) (layers "B.Cu" "B.Paste" "B.Mask")
      (net 133 "5V_SYS") (pinfunction "VIN") (pintype "power_in"))
    (pad "4" smd rect (at 0.947 1.18 270) (size 0.7 0.8) (layers "B.Cu" "B.Paste" "B.Mask")
      (net 172 "Net-(R139-Pad2)") (pinfunction "FB") (pintype "input"))
    (pad "5" smd rect (at -0.001 1.18 270) (size 0.7 0.8) (layers "B.Cu" "B.Paste" "B.Mask")
      (net 408 "Net-(R128-Pad2)") (pinfunction "EN") (pintype "input"))
    (pad "6" smd rect (at -0.952 1.18 270) (size 0.7 0.8) (layers "B.Cu" "B.Paste" "B.Mask")
      (net 361 "Net-(C134-Pad1)") (pinfunction "BST") (pintype "output"))
  )
	(footprint "sa800u-baseboard-hw-footprints:C_0402_1005Metric" (layer "B.Cu")
    (tedit 616D63CF)
    (at 121.85 120.9 180)
    (descr "Capacitor SMD 0402")
    (tags "capacitor SMD 0402")
    (property "Author" "Antmicro")
    (property "Dielectric" "X5R")
    (property "License" "Apache-2.0")
    (property "MPN" "GRM155R61H104KE14D")
    (property "Manufacturer" "Murata")
    (property "Sheetfile" "psu.kicad_sch")
    (property "Sheetname" "PSU")
    (property "Val" "100n")
    (property "Voltage" "50V")
    (attr smd)
    (fp_text reference "C134" (at 0.83 -0.32) (layer "B.SilkS")
      (effects (font (size 0.7 0.7) (thickness 0.15)) (justify left bottom mirror))
    )
    (fp_text value "C_100n_0402" (at 0 -1.4) (layer "B.Fab")
      (effects (font (size 0.7 0.7) (thickness 0.15)) (justify left bottom mirror))
    )
    (fp_text user "Author: Antmicro" (at -0.932 -4.17) (layer "B.Fab") hide
      (effects (font (size 0.7 0.7) (thickness 0.15)) (justify left bottom mirror))
    )
    (fp_text user "License: Apache-2.0" (at -0.932 -5.17) (layer "B.Fab") hide
      (effects (font (size 0.7 0.7) (thickness 0.15)) (justify left bottom mirror))
    )
    (fp_text user "${REFERENCE}" (at -0.932 -3.168) (layer "B.Fab") hide
      (effects (font (size 0.7 0.7) (thickness 0.15)) (justify left bottom mirror))
    )
    (fp_rect (start -0.94 0.47) (end 0.94 -0.47) (layer "B.CrtYd") (width 0.05) (fill none))
    (fp_rect (start -0.499 0.249) (end 0.499 -0.249) (layer "B.Fab") (width 0.15) (fill none))
    (pad "1" smd roundrect (at -0.484 0 180) (size 0.59 0.64) (layers "B.Cu" "B.Paste" "B.Mask") (roundrect_rratio 0.25)
      (net 361 "Net-(C134-Pad1)") (pintype "passive"))
    (pad "2" smd roundrect (at 0.484 0 180) (size 0.59 0.64) (layers "B.Cu" "B.Paste" "B.Mask") (roundrect_rratio 0.25)
      (net 360 "Net-(C134-Pad2)") (pintype "passive"))
  )
	(footprint "sa800u-baseboard-hw-footprints:R_0402_1005Metric" (layer "B.Cu")
    (tedit 5FD9C158)
    (at 121.85 124.05)
    (descr "Resistor SMD 0402")
    (tags "resistor SMD 0402")
    (property "Author" "Antmicro")
    (property "License" "Apache-2.0")
    (property "MPN" "CR0402-FX-1002GLF")
    (property "Manufacturer" "Bourns")
    (property "Sheetfile" "psu.kicad_sch")
    (property "Sheetname" "PSU")
    (property "Tolerance" "1%")
    (property "Val" "10k")
    (attr smd)
    (fp_text reference "R139" (at -0.84 0.37 180) (layer "B.SilkS")
      (effects (font (size 0.7 0.7) (thickness 0.15)) (justify left bottom mirror))
    )
    (fp_text value "R_10k_0402" (at 0 -1.4 180) (layer "B.Fab")
      (effects (font (size 0.7 0.7) (thickness 0.15)) (justify left bottom mirror))
    )
    (fp_text user "License: Apache-2.0" (at -0.95 -5.169 180) (layer "B.Fab") hide
      (effects (font (size 0.7 0.7) (thickness 0.15)) (justify left bottom mirror))
    )
    (fp_text user "${REFERENCE}" (at -0.95 -3.168 180) (layer "B.Fab") hide
      (effects (font (size 0.7 0.7) (thickness 0.15)) (justify left bottom mirror))
    )
    (fp_text user "Author: Antmicro" (at -0.95 -4.169 180) (layer "B.Fab") hide
      (effects (font (size 0.7 0.7) (thickness 0.15)) (justify left bottom mirror))
    )
    (fp_rect (start -0.93 0.47) (end 0.93 -0.47) (layer "B.CrtYd") (width 0.05) (fill none))
    (fp_rect (start -0.5 0.25) (end 0.5 -0.25) (layer "B.Fab") (width 0.15) (fill none))
    (pad "1" smd roundrect (at -0.485 0) (size 0.59 0.64) (layers "B.Cu" "B.Paste" "B.Mask") (roundrect_rratio 0.25)
      (net 138 "1V2_SYS") (pintype "passive"))
    (pad "2" smd roundrect (at 0.485 0) (size 0.59 0.64) (layers "B.Cu" "B.Paste" "B.Mask") (roundrect_rratio 0.25)
      (net 172 "Net-(R139-Pad2)") (pintype "passive"))
  )
	(footprint "sa800u-baseboard-hw-footprints:C_0603_1608Metric" (layer "B.Cu")
    (tedit 5D5E94D2)
    (at 126.85 125.04)
    (descr "Capacitor SMD 0603")
    (tags "capacitor 0603")
    (property "Author" "Antmicro")
    (property "Dielectric" "")
    (property "License" "Apache-2.0")
    (property "MPN" "GRM188R60J226MEA0D")
    (property "Manufacturer" "Murata")
    (property "Sheetfile" "psu.kicad_sch")
    (property "Sheetname" "PSU")
    (property "Val" "22u")
    (property "Voltage" "")
    (attr smd)
    (fp_text reference "C130" (at 1.33 1.61 180) (layer "B.SilkS")
      (effects (font (size 0.7 0.7) (thickness 0.15)) (justify left bottom mirror))
    )
    (fp_text value "C_22u_0603" (at 0 -1.6 180) (layer "B.Fab")
      (effects (font (size 0.7 0.7) (thickness 0.15)) (justify left bottom mirror))
    )
    (fp_text user "${REFERENCE}" (at -1.682 -3.895 180) (layer "B.Fab") hide
      (effects (font (size 0.7 0.7) (thickness 0.15)) (justify left bottom mirror))
    )
    (fp_text user "License: Apache-2.0" (at -1.682 -5.895 180) (layer "B.Fab") hide
      (effects (font (size 0.7 0.7) (thickness 0.15)) (justify left bottom mirror))
    )
    (fp_text user "Author: Antmicro" (at -1.682 -4.894 180) (layer "B.Fab") hide
      (effects (font (size 0.7 0.7) (thickness 0.15)) (justify left bottom mirror))
    )
    (fp_line (start -0.3 0.3) (end 0.3 0.3) (layer "B.SilkS") (width 0.15))
    (fp_line (start -0.3 -0.3) (end 0.3 -0.3) (layer "B.SilkS") (width 0.15))
    (fp_rect (start -1.24 0.7) (end 1.24 -0.7) (layer "B.CrtYd") (width 0.05) (fill none))
    (fp_rect (start -0.8 0.4) (end 0.8 -0.4) (layer "B.Fab") (width 0.15) (fill none))
    (pad "1" smd roundrect (at -0.7 0) (size 0.6 0.8) (layers "B.Cu" "B.Paste" "B.Mask") (roundrect_rratio 0.2)
      (net 133 "5V_SYS") (pintype "passive"))
    (pad "2" smd roundrect (at 0.7 0) (size 0.6 0.8) (layers "B.Cu" "B.Paste" "B.Mask") (roundrect_rratio 0.2)
      (net 1 "GND") (pintype "passive"))
  )
	(footprint "sa800u-baseboard-hw-footprints:C_0603_1608Metric" (layer "B.Cu")
    (tedit 5D5E94D2)
    (at 129.55 125.04 180)
    (descr "Capacitor SMD 0603")
    (tags "capacitor 0603")
    (property "Author" "Antmicro")
    (property "Dielectric" "")
    (property "License" "Apache-2.0")
    (property "MPN" "GRM188R60J226MEA0D")
    (property "Manufacturer" "Murata")
    (property "Sheetfile" "psu.kicad_sch")
    (property "Sheetname" "PSU")
    (property "Val" "22u")
    (property "Voltage" "")
    (attr smd)
    (fp_text reference "C140" (at -1.48 -2.88) (layer "B.SilkS")
      (effects (font (size 0.7 0.7) (thickness 0.15)) (justify left bottom mirror))
    )
    (fp_text value "C_22u_0603" (at 0 -1.6) (layer "B.Fab")
      (effects (font (size 0.7 0.7) (thickness 0.15)) (justify left bottom mirror))
    )
    (fp_text user "Author: Antmicro" (at -1.682 -4.894) (layer "B.Fab") hide
      (effects (font (size 0.7 0.7) (thickness 0.15)) (justify left bottom mirror))
    )
    (fp_text user "${REFERENCE}" (at -1.682 -3.895) (layer "B.Fab") hide
      (effects (font (size 0.7 0.7) (thickness 0.15)) (justify left bottom mirror))
    )
    (fp_text user "License: Apache-2.0" (at -1.682 -5.895) (layer "B.Fab") hide
      (effects (font (size 0.7 0.7) (thickness 0.15)) (justify left bottom mirror))
    )
    (fp_line (start -0.3 -0.3) (end 0.3 -0.3) (layer "B.SilkS") (width 0.15))
    (fp_line (start -0.3 0.3) (end 0.3 0.3) (layer "B.SilkS") (width 0.15))
    (fp_rect (start -1.24 0.7) (end 1.24 -0.7) (layer "B.CrtYd") (width 0.05) (fill none))
    (fp_rect (start -0.8 0.4) (end 0.8 -0.4) (layer "B.Fab") (width 0.15) (fill none))
    (pad "1" smd roundrect (at -0.7 0 180) (size 0.6 0.8) (layers "B.Cu" "B.Paste" "B.Mask") (roundrect_rratio 0.2)
      (net 138 "1V2_SYS") (pintype "passive"))
    (pad "2" smd roundrect (at 0.7 0 180) (size 0.6 0.8) (layers "B.Cu" "B.Paste" "B.Mask") (roundrect_rratio 0.2)
      (net 1 "GND") (pintype "passive"))
  )
	(footprint "sa800u-baseboard-hw-footprints:R_0402_1005Metric" (layer "B.Cu")
    (tedit 5FD9C158)
    (at 121.85 123.05)
    (descr "Resistor SMD 0402")
    (tags "resistor SMD 0402")
    (property "Author" "Antmicro")
    (property "License" "Apache-2.0")
    (property "MPN" "CR0402-FX-2002GLF")
    (property "Manufacturer" "Bourns")
    (property "Sheetfile" "psu.kicad_sch")
    (property "Sheetname" "PSU")
    (property "Tolerance" "1%")
    (property "Val" "20k")
    (attr smd)
    (fp_text reference "R140" (at -0.84 0.37 180) (layer "B.SilkS")
      (effects (font (size 0.7 0.7) (thickness 0.15)) (justify left bottom mirror))
    )
    (fp_text value "R_20k_0402" (at 0 -1.4 180) (layer "B.Fab")
      (effects (font (size 0.7 0.7) (thickness 0.15)) (justify left bottom mirror))
    )
    (fp_text user "${REFERENCE}" (at -0.95 -3.168 180) (layer "B.Fab") hide
      (effects (font (size 0.7 0.7) (thickness 0.15)) (justify left bottom mirror))
    )
    (fp_text user "Author: Antmicro" (at -0.95 -4.169 180) (layer "B.Fab") hide
      (effects (font (size 0.7 0.7) (thickness 0.15)) (justify left bottom mirror))
    )
    (fp_text user "License: Apache-2.0" (at -0.95 -5.169 180) (layer "B.Fab") hide
      (effects (font (size 0.7 0.7) (thickness 0.15)) (justify left bottom mirror))
    )
    (fp_rect (start -0.93 0.47) (end 0.93 -0.47) (layer "B.CrtYd") (width 0.05) (fill none))
    (fp_rect (start -0.5 0.25) (end 0.5 -0.25) (layer "B.Fab") (width 0.15) (fill none))
    (pad "1" smd roundrect (at -0.485 0) (size 0.59 0.64) (layers "B.Cu" "B.Paste" "B.Mask") (roundrect_rratio 0.25)
      (net 1 "GND") (pintype "passive"))
    (pad "2" smd roundrect (at 0.485 0) (size 0.59 0.64) (layers "B.Cu" "B.Paste" "B.Mask") (roundrect_rratio 0.25)
      (net 172 "Net-(R139-Pad2)") (pintype "passive"))
  )
	(footprint "sa800u-baseboard-hw-footprints:C_0402_1005Metric" (layer "B.Cu")
    (tedit 616D63CF)
    (at 136.75 134.95 90)
    (descr "Capacitor SMD 0402")
    (tags "capacitor SMD 0402")
    (property "Author" "Antmicro")
    (property "DNP" "DNP")
    (property "Dielectric" "C0G")
    (property "License" "Apache-2.0")
    (property "MPN" "GCM1555C1H100GA16D")
    (property "Manufacturer" "Murata")
    (property "Sheetfile" "hdmi-converter.kicad_sch")
    (property "Sheetname" "HDMI converter")
    (property "Val" "10p")
    (property "Voltage" "50V")
    (attr exclude_from_pos_files)
    (fp_text reference "C57" (at -0.85 0.37 270) (layer "B.SilkS")
      (effects (font (size 0.7 0.7) (thickness 0.15)) (justify left bottom mirror))
    )
    (fp_text value "C_10p_0402" (at 0 -1.4 270) (layer "B.Fab")
      (effects (font (size 0.7 0.7) (thickness 0.15)) (justify left bottom mirror))
    )
    (fp_text user "License: Apache-2.0" (at -0.932 -5.17 270) (layer "B.Fab") hide
      (effects (font (size 0.7 0.7) (thickness 0.15)) (justify left bottom mirror))
    )
    (fp_text user "Author: Antmicro" (at -0.932 -4.17 270) (layer "B.Fab") hide
      (effects (font (size 0.7 0.7) (thickness 0.15)) (justify left bottom mirror))
    )
    (fp_text user "${REFERENCE}" (at -0.932 -3.168 270) (layer "B.Fab") hide
      (effects (font (size 0.7 0.7) (thickness 0.15)) (justify left bottom mirror))
    )
    (fp_rect (start -0.94 0.47) (end 0.94 -0.47) (layer "B.CrtYd") (width 0.05) (fill none))
    (fp_rect (start -0.499 0.249) (end 0.499 -0.249) (layer "B.Fab") (width 0.15) (fill none))
    (pad "1" smd roundrect (at -0.484 0 90) (size 0.59 0.64) (layers "B.Cu" "B.Paste" "B.Mask") (roundrect_rratio 0.25)
      (net 208 "/HDMI converter/HDMI_CLK_N") (pintype "passive"))
    (pad "2" smd roundrect (at 0.484 0 90) (size 0.59 0.64) (layers "B.Cu" "B.Paste" "B.Mask") (roundrect_rratio 0.25)
      (net 1 "GND") (pintype "passive"))
  )
)
